# S9S_MB_2U (Grand Teton) — schematic netlist excerpt (pin names and nets, part order shuffled) for the footprints in the layout excerpt that follows; sources: Cadence DE-HDL packaged netlist, KiCad conversion of 03242023_DA0F0TMBIJ0_F0T_Motherboard_J_brd_V01_OCP.brd

J24  SCONN288_ADR50017P087CC  SCONN288_ADR50017-P087CC IO  pkg DDR288S_1-1VXB  page 105
  VIN_BULK0  = P12V_S3_AUX_CPU1_NVDIMM
  RFU0  = TP_CHD_CPU1_DIMM2_FRU_0
  VIN_MGMT  = P3V3_AUX
  HSCL  = I3C_SPD_DDRABCD_CPU1_LVC1_SCL_7
  HSDA  = I3C_SPD_DDRABCD_CPU1_LVC1_SDA
  VSS0  = GND
  DQ0_A  = M_D_CPU1_SA_DQ<0>
  VSS1  = GND
  DQ1_A  = M_D_CPU1_SA_DQ<1>
  VSS2  = GND
  DQS0_A_T  = M_D_CPU1_SA_DQS_DP<0>
  DQS0_A_C  = M_D_CPU1_SA_DQS_DN<0>
  VSS3  = GND
  DQ4_A  = M_D_CPU1_SA_DQ<4>
  VSS4  = GND
  DQ5_A  = M_D_CPU1_SA_DQ<5>
  VSS5  = GND
  DQ8_A  = M_D_CPU1_SA_DQ<8>
  VSS6  = GND
  DQ9_A  = M_D_CPU1_SA_DQ<9>
  VSS7  = GND
  DQS1_A_T  = M_D_CPU1_SA_DQS_DP<1>
  DQS1_A_C  = M_D_CPU1_SA_DQS_DN<1>
  VSS8  = GND
  DQ12_A  = M_D_CPU1_SA_DQ<12>
  VSS9  = GND
  DQ13_A  = M_D_CPU1_SA_DQ<13>
  VSS10  = GND
  DQ16_A  = M_D_CPU1_SA_DQ<16>
  VSS11  = GND
  DQ17_A  = M_D_CPU1_SA_DQ<17>
  VSS12  = GND
  DQS2_A_T  = M_D_CPU1_SA_DQS_DP<2>
  DQS2_A_C  = M_D_CPU1_SA_DQS_DN<2>
  VSS13  = GND
  DQ20_A  = M_D_CPU1_SA_DQ<20>
  VSS14  = GND
  DQ21_A  = M_D_CPU1_SA_DQ<21>
  VSS15  = GND
  DQ24_A  = M_D_CPU1_SA_DQ<24>
  VSS16  = GND
  DQ25_A  = M_D_CPU1_SA_DQ<25>
  VSS17  = GND
  DQS3_A_T  = M_D_CPU1_SA_DQS_DP<3>
  DQS3_A_C  = M_D_CPU1_SA_DQS_DN<3>
  VSS18  = GND
  DQ28_A  = M_D_CPU1_SA_DQ<28>
  VSS19  = GND
  DQ29_A  = M_D_CPU1_SA_DQ<29>
  VSS20  = GND
  CB0_A  = M_D_CPU1_SA_CB<0>
  VSS21  = GND
  CB1_A  = M_D_CPU1_SA_CB<1>
  VSS22  = GND
  DQS4_A_T  = M_D_CPU1_SA_DQS_DP<4>
  DQS4_A_C  = M_D_CPU1_SA_DQS_DN<4>
  VSS23  = GND
  CB4_A  = M_D_CPU1_SA_CB<4>
  VSS24  = GND
  CB5_A  = M_D_CPU1_SA_CB<5>
  VSS25  = GND
  ALERT_N  = M_D_CPU1_ALERT_N
  VSS26  = GND
  CS0_A_N  = M_D_CPU1_SA_CS_N<2>
  VSS27  = GND
  CA0_A  = M_D_CPU1_SA_CA<0>
  VSS28  = GND
  CA2_A  = M_D_CPU1_SA_CA<2>
  VSS29  = GND
  CA4_A  = M_D_CPU1_SA_CA<4>
  VSS30  = GND
  CA6_A  = M_D_CPU1_SA_CA<6>
  VSS31  = GND
  PAR_A  = M_D_CPU1_SA_PAR
  VSS32  = GND
  CA0_B  = M_D_CPU1_SB_CA<0>
  VSS33  = GND
  CA2_B  = M_D_CPU1_SB_CA<2>
  VSS34  = GND
  CA4_B  = M_D_CPU1_SB_CA<4>
  VSS35  = GND
  CA6_B  = M_D_CPU1_SB_CA<6>
  VSS36  = GND
  CS0_B_N  = M_D_CPU1_SB_CS_N<2>
  VSS37  = GND
  \lbd||rsp_a_n\  = M_D_CPU1_SA_RSP<1>
  \lbs||rsp_b_n\  = M_D_CPU1_SB_RSP<1>
  VSS38  = GND
  CB4_B  = M_D_CPU1_SB_CB<4>
  VSS39  = GND
  CB5_B  = M_D_CPU1_SB_CB<5>
  VSS40  = GND
  \dqs9_b_t||tdqs9_b_t||dbi4_b_n\  = M_D_CPU1_SB_DQS_DP<9>
  \dqs9_b_c||tdqs9_b_c\  = M_D_CPU1_SB_DQS_DN<9>
  VSS41  = GND
  CB0_B  = M_D_CPU1_SB_CB<0>
  VSS42  = GND
  CB1_B  = M_D_CPU1_SB_CB<1>
  VSS43  = GND
  DQ0_B  = M_D_CPU1_SB_DQ<0>
  VSS44  = GND
  DQ1_B  = M_D_CPU1_SB_DQ<1>
  VSS45  = GND
  DQS0_B_T  = M_D_CPU1_SB_DQS_DP<0>
  DQS0_B_C  = M_D_CPU1_SB_DQS_DN<0>
  VSS46  = GND
  DQ4_B  = M_D_CPU1_SB_DQ<4>
  VSS47  = GND
  DQ5_B  = M_D_CPU1_SB_DQ<5>
  VSS48  = GND
  DQ8_B  = M_D_CPU1_SB_DQ<8>
  VSS49  = GND
  DQ9_B  = M_D_CPU1_SB_DQ<9>
  VSS50  = GND
  DQS1_B_T  = M_D_CPU1_SB_DQS_DP<1>
  DQS1_B_C  = M_D_CPU1_SB_DQS_DN<1>
  VSS51  = GND
  DQ12_B  = M_D_CPU1_SB_DQ<12>
  VSS52  = GND
  DQ13_B  = M_D_CPU1_SB_DQ<13>
  VSS53  = GND
  DQ16_B  = M_D_CPU1_SB_DQ<16>
  VSS54  = GND
  DQ17_B  = M_D_CPU1_SB_DQ<17>
  VSS55  = GND
  DQS2_B_T  = M_D_CPU1_SB_DQS_DP<2>
  DQS2_B_C  = M_D_CPU1_SB_DQS_DN<2>
  VSS56  = GND
  DQ20_B  = M_D_CPU1_SB_DQ<20>
  VSS57  = GND
  DQ21_B  = M_D_CPU1_SB_DQ<21>
  VSS58  = GND
  DQ24_B  = M_D_CPU1_SB_DQ<24>
  VSS59  = GND
  DQ25_B  = M_D_CPU1_SB_DQ<25>
  VSS60  = GND
  DQS3_B_T  = M_D_CPU1_SB_DQS_DP<3>
  DQS3_B_C  = M_D_CPU1_SB_DQS_DN<3>
  VSS61  = GND
  DQ28_B  = M_D_CPU1_SB_DQ<28>
  VSS62  = GND
  DQ29_B  = M_D_CPU1_SB_DQ<29>
  VSS63  = GND
  RFU1  = TP_CHD_CPU1_DIMM2_FRU_1
  VIN_BULK1  = P12V_S3_AUX_CPU1_NVDIMM
  VIN_BULK2  = P12V_S3_AUX_CPU1_NVDIMM
  \pwr_good||fail_n\  = PWRGD_CHD_CPU1_DIMM2
  HSA  = PD_CHD_CPU1_DIMM2_SAA
  RFU2  = TP_CHD_CPU1_DIMM2_FRU_2
  RFU3  = TP_CHD_CPU1_DIMM2_FRU_3
  VSS64  = GND
  DQ2_A  = M_D_CPU1_SA_DQ<2>
  VSS65  = GND
  DQ3_A  = M_D_CPU1_SA_DQ<3>
  VSS66  = GND
  \dqs5_a_c||tdqs5_a_c||dqs5_a_t||tdqs5_a_t\  = M_D_CPU1_SA_DQS_DN<5>
  \dqs5_a_t||tdqs5_a_t\  = M_D_CPU1_SA_DQS_DP<5>
  VSS67  = GND
  DQ6_A  = M_D_CPU1_SA_DQ<6>
  VSS68  = GND
  DQ7_A  = M_D_CPU1_SA_DQ<7>
  VSS69  = GND
  DQ10_A  = M_D_CPU1_SA_DQ<10>
  VSS70  = GND
  DQ11_A  = M_D_CPU1_SA_DQ<11>
  VSS71  = GND
  \dqs6_a_c||tdqs6_a_c||dqs6_a_t||tdqs6_a_t\  = M_D_CPU1_SA_DQS_DN<6>
  \dqs6_a_t||tdqs6_a_t\  = M_D_CPU1_SA_DQS_DP<6>
  VSS72  = GND
  DQ14_A  = M_D_CPU1_SA_DQ<14>
  VSS73  = GND
  DQ15_A  = M_D_CPU1_SA_DQ<15>
  VSS74  = GND
  DQ18_A  = M_D_CPU1_SA_DQ<18>
  VSS75  = GND
  DQ19_A  = M_D_CPU1_SA_DQ<19>
  VSS76  = GND
  \dqs7_a_c||tdqs7_a_c\  = M_D_CPU1_SA_DQS_DN<7>
  \dqs7_a_t||tdqs7_a_t\  = M_D_CPU1_SA_DQS_DP<7>
  VSS77  = GND
  DQ22_A  = M_D_CPU1_SA_DQ<22>
  VSS78  = GND
  DQ23_A  = M_D_CPU1_SA_DQ<23>
  VSS79  = GND
  DQ26_A  = M_D_CPU1_SA_DQ<26>
  VSS80  = GND
  DQ27_A  = M_D_CPU1_SA_DQ<27>
  VSS81  = GND
  \dqs8_a_c||tdqs8_a_c\  = M_D_CPU1_SA_DQS_DN<8>
  \dqs8_a_t||tdqs8_a_t\  = M_D_CPU1_SA_DQS_DP<8>
  VSS82  = GND
  DQ30_A  = M_D_CPU1_SA_DQ<30>
  VSS83  = GND
  DQ31_A  = M_D_CPU1_SA_DQ<31>
  VSS84  = GND
  CB2_A  = M_D_CPU1_SA_CB<2>
  VSS85  = GND
  CB3_A  = M_D_CPU1_SA_CB<3>
  VSS86  = GND
  \dqs9_a_c||tdqs9_a_c\  = M_D_CPU1_SA_DQS_DN<9>
  \dqs9_a_t||tdqs9_a_t\  = M_D_CPU1_SA_DQS_DP<9>
  VSS87  = GND
  CB6_A  = M_D_CPU1_SA_CB<6>
  VSS88  = GND
  CB7_A  = M_D_CPU1_SA_CB<7>
  VSS89  = GND
  RESET_N  = RST_M_CD_CPU1_FPGA_N
  VSS90  = GND
  CS1_A_N  = M_D_CPU1_SA_CS_N<3>
  VSS91  = GND
  CA1_A  = M_D_CPU1_SA_CA<1>
  VSS92  = GND
  CA3_A  = M_D_CPU1_SA_CA<3>
  VSS93  = GND
  CA5_A  = M_D_CPU1_SA_CA<5>
  VSS94  = GND
  CK_T  = M_D_CPU1_CLK_DP<1>
  CK_C  = M_D_CPU1_CLK_DN<1>
  VSS95  = GND
  RFU4  = TP_CHD_CPU1_DIMM2_FRU_4
  CA1_B  = M_D_CPU1_SB_CA<1>
  VSS96  = GND
  CA3_B  = M_D_CPU1_SB_CA<3>
  VSS97  = GND
  CA5_B  = M_D_CPU1_SB_CA<5>
  VSS98  = GND
  PAR_B  = M_D_CPU1_SB_PAR
  VSS99  = GND
  CS1_B_N  = M_D_CPU1_SB_CS_N<3>
  VSS100  = GND
  RFU5  = TP_CHD_CPU1_DIMM2_FRU_5
  RFU6  = TP_CHD_CPU1_DIMM2_FRU_6
  VSS101  = GND
  CB6_B  = M_D_CPU1_SB_CB<6>
  VSS102  = GND
  CB7_B  = M_D_CPU1_SB_CB<7>
  VSS103  = GND
  DQS4_B_C  = M_D_CPU1_SB_DQS_DN<4>
  DQS4_B_T  = M_D_CPU1_SB_DQS_DP<4>
  VSS104  = GND
  CB2_B  = M_D_CPU1_SB_CB<2>
  VSS105  = GND
  CB3_B  = M_D_CPU1_SB_CB<3>
  VSS106  = GND
  DQ2_B  = M_D_CPU1_SB_DQ<2>
  VSS107  = GND
  DQ3_B  = M_D_CPU1_SB_DQ<3>
  VSS108  = GND
  \dqs5_b_c||tdqs5_b_c\  = M_D_CPU1_SB_DQS_DN<5>
  \dqs5_b_t||tdqs5_b_t\  = M_D_CPU1_SB_DQS_DP<5>
  VSS109  = GND
  DQ6_B  = M_D_CPU1_SB_DQ<6>
  VSS110  = GND
  DQ7_B  = M_D_CPU1_SB_DQ<7>
  VSS111  = GND
  DQ10_B  = M_D_CPU1_SB_DQ<10>
  VSS112  = GND
  DQ11_B  = M_D_CPU1_SB_DQ<11>
  VSS113  = GND
  \dqs6_b_c||tdqs6_b_c\  = M_D_CPU1_SB_DQS_DN<6>
  \dqs6_b_t||tdqs6_b_t\  = M_D_CPU1_SB_DQS_DP<6>
  VSS114  = GND
  DQ14_B  = M_D_CPU1_SB_DQ<14>
  VSS115  = GND
  DQ15_B  = M_D_CPU1_SB_DQ<15>
  VSS116  = GND
  DQ18_B  = M_D_CPU1_SB_DQ<18>
  VSS117  = GND
  DQ19_B  = M_D_CPU1_SB_DQ<19>
  VSS118  = GND
  \dqs7_b_c||tdqs7_b_c\  = M_D_CPU1_SB_DQS_DN<7>
  \dqs7_b_t||tdqs7_b_t\  = M_D_CPU1_SB_DQS_DP<7>
  VSS119  = GND
  DQ22_B  = M_D_CPU1_SB_DQ<22>
  VSS120  = GND
  DQ23_B  = M_D_CPU1_SB_DQ<23>
  VSS121  = GND
  DQ26_B  = M_D_CPU1_SB_DQ<26>
  VSS122  = GND
  DQ27_B  = M_D_CPU1_SB_DQ<27>
  VSS123  = GND
  \dqs8_b_c||tdqs8_b_c\  = M_D_CPU1_SB_DQS_DN<8>
  \dqs8_b_t||tdqs8_b_t\  = M_D_CPU1_SB_DQS_DP<8>
  VSS124  = GND
  DQ30_B  = M_D_CPU1_SB_DQ<30>
  VSS125  = GND
  DQ31_B  = M_D_CPU1_SB_DQ<31>
  VSS126  = GND
  G1  = GND
  G2  = GND
  G3  = GND

(kicad_pcb
	(version 20260206)
	(generator "pcbnew")
	(generator_version "10.0")
	(general
		(thickness 1.6)
		(legacy_teardrops no)
	)
	(paper "A4")
	(title_block
		(title "03242023_DA0F0TMBIJ0_F0T_Motherboard_J_brd_V01_OCP.brd")
		(comment 1 "Grand Teton / footprint 1660 of 6105 (J24), pads 138-182 of 291")
	)
	(layers
		(0 "F.Cu" signal "TOP")
		(4 "In1.Cu" signal "GND")
		(6 "In2.Cu" signal "IN1")
		(8 "In3.Cu" signal "GND1")
		(10 "In4.Cu" signal "IN2")
		(12 "In5.Cu" signal "GND2")
		(14 "In6.Cu" signal "IN3")
		(16 "In7.Cu" signal "GND3")
		(18 "In8.Cu" signal "VCC")
		(20 "In9.Cu" signal "VCC1")
		(22 "In10.Cu" signal "GND4")
		(24 "In11.Cu" signal "IN4")
		(26 "In12.Cu" signal "GND5")
		(28 "In13.Cu" signal "IN5")
		(30 "In14.Cu" signal "GND6")
		(32 "In15.Cu" signal "IN6")
		(34 "In16.Cu" signal "GND7")
		(2 "B.Cu" signal "BOTTOM")
		(9 "F.Adhes" user "F.Adhesive")
		(11 "B.Adhes" user "B.Adhesive")
		(13 "F.Paste" user "Package Geometry/Pastemask Top")
		(15 "B.Paste" user "Package Geometry/Pastemask Bottom")
		(5 "F.SilkS" user "Ref Des/Silkscreen Top")
		(7 "B.SilkS" user "Ref Des/Silkscreen Bottom")
		(1 "F.Mask" user "Board Geometry/Soldermask Top")
		(3 "B.Mask" user "Board Geometry/Soldermask Bottom")
		(17 "Dwgs.User" user "User.Drawings")
		(19 "Cmts.User" user "User.Comments")
		(21 "Eco1.User" user "User.Eco1")
		(23 "Eco2.User" user "User.Eco2")
		(25 "Edge.Cuts" user "Board Geometry/Outline")
		(27 "Margin" user)
		(31 "F.CrtYd" user "Package Geometry/Place Bound Top")
		(29 "B.CrtYd" user "Package Geometry/Place Bound Bottom")
		(35 "F.Fab" user "Ref Des/Assembly Top")
		(33 "B.Fab" user "Ref Des/Assembly Bottom")
	)
	(footprint ""
		(layer "F.Cu")
		(at 17.73428 -258.091686)
		(property "Reference" "J24"
			(at -3.0607 -81.901792 0)
			(unlocked yes)
			(layer "F.SilkS")
			(effects
				(font
					(size 0.7874 0.5842)
					(thickness 0.1524)
				)
				(justify left)
			)
		)
		(property "Value" ""
			(at 0 0 0)
			(layer "F.Fab")
			(effects
				(font
					(size 1.27 1.27)
				)
			)
		)
		(duplicate_pad_numbers_are_jumpers no)
		(pad "138" smd rect
			(at -2.050034 58.224928 270)
			(size 0.519938 1.4986)
			(layers "F.Cu" "F.Mask" "F.Paste")
			(net "M_D_CPU1_SB_DQS_DN<3>")
		)
		(pad "139" smd rect
			(at -2.050034 59.075066 270)
			(size 0.519938 1.4986)
			(layers "F.Cu" "F.Mask" "F.Paste")
			(net "GND")
		)
		(pad "140" smd rect
			(at -2.050034 59.92495 270)
			(size 0.519938 1.4986)
			(layers "F.Cu" "F.Mask" "F.Paste")
			(net "M_D_CPU1_SB_DQ<28>")
		)
		(pad "141" smd rect
			(at -2.050034 60.775088 270)
			(size 0.519938 1.4986)
			(layers "F.Cu" "F.Mask" "F.Paste")
			(net "GND")
		)
		(pad "142" smd rect
			(at -2.050034 61.624972 270)
			(size 0.519938 1.4986)
			(layers "F.Cu" "F.Mask" "F.Paste")
			(net "M_D_CPU1_SB_DQ<29>")
		)
		(pad "143" smd rect
			(at -2.050034 62.47511 270)
			(size 0.519938 1.4986)
			(layers "F.Cu" "F.Mask" "F.Paste")
			(net "GND")
		)
		(pad "144" smd rect
			(at -2.050034 63.324994 270)
			(size 0.519938 1.4986)
			(layers "F.Cu" "F.Mask" "F.Paste")
			(net "TP_CHD_CPU1_DIMM2_FRU_1")
		)
		(pad "145" smd rect
			(at 2.050034 -63.324994 270)
			(size 0.519938 1.4986)
			(layers "F.Cu" "F.Mask" "F.Paste")
			(net "P12V_S3_AUX_CPU1_NVDIMM")
		)
		(pad "146" smd rect
			(at 2.050034 -62.47511 270)
			(size 0.519938 1.4986)
			(layers "F.Cu" "F.Mask" "F.Paste")
			(net "P12V_S3_AUX_CPU1_NVDIMM")
		)
		(pad "147" smd rect
			(at 2.050034 -61.624972 270)
			(size 0.519938 1.4986)
			(layers "F.Cu" "F.Mask" "F.Paste")
			(net "PWRGD_CHD_CPU1_DIMM2")
		)
		(pad "148" smd rect
			(at 2.050034 -60.775088 270)
			(size 0.519938 1.4986)
			(layers "F.Cu" "F.Mask" "F.Paste")
			(net "PD_CHD_CPU1_DIMM2_SAA")
		)
		(pad "149" smd rect
			(at 2.050034 -59.92495 270)
			(size 0.519938 1.4986)
			(layers "F.Cu" "F.Mask" "F.Paste")
			(net "TP_CHD_CPU1_DIMM2_FRU_2")
		)
		(pad "150" smd rect
			(at 2.050034 -59.075066 270)
			(size 0.519938 1.4986)
			(layers "F.Cu" "F.Mask" "F.Paste")
			(net "TP_CHD_CPU1_DIMM2_FRU_3")
		)
		(pad "151" smd rect
			(at 2.050034 -58.224928 270)
			(size 0.519938 1.4986)
			(layers "F.Cu" "F.Mask" "F.Paste")
			(net "GND")
		)
		(pad "152" smd rect
			(at 2.050034 -57.375044 270)
			(size 0.519938 1.4986)
			(layers "F.Cu" "F.Mask" "F.Paste")
			(net "M_D_CPU1_SA_DQ<2>")
		)
		(pad "153" smd rect
			(at 2.050034 -56.524906 270)
			(size 0.519938 1.4986)
			(layers "F.Cu" "F.Mask" "F.Paste")
			(net "GND")
		)
		(pad "154" smd rect
			(at 2.050034 -55.675022 270)
			(size 0.519938 1.4986)
			(layers "F.Cu" "F.Mask" "F.Paste")
			(net "M_D_CPU1_SA_DQ<3>")
		)
		(pad "155" smd rect
			(at 2.050034 -54.824884 270)
			(size 0.519938 1.4986)
			(layers "F.Cu" "F.Mask" "F.Paste")
			(net "GND")
		)
		(pad "156" smd rect
			(at 2.050034 -53.975 270)
			(size 0.519938 1.4986)
			(layers "F.Cu" "F.Mask" "F.Paste")
			(net "M_D_CPU1_SA_DQS_DN<5>")
		)
		(pad "157" smd rect
			(at 2.050034 -53.125116 270)
			(size 0.519938 1.4986)
			(layers "F.Cu" "F.Mask" "F.Paste")
			(net "M_D_CPU1_SA_DQS_DP<5>")
		)
		(pad "158" smd rect
			(at 2.050034 -52.274978 270)
			(size 0.519938 1.4986)
			(layers "F.Cu" "F.Mask" "F.Paste")
			(net "GND")
		)
		(pad "159" smd rect
			(at 2.050034 -51.425094 270)
			(size 0.519938 1.4986)
			(layers "F.Cu" "F.Mask" "F.Paste")
			(net "M_D_CPU1_SA_DQ<6>")
		)
		(pad "160" smd rect
			(at 2.050034 -50.574956 270)
			(size 0.519938 1.4986)
			(layers "F.Cu" "F.Mask" "F.Paste")
			(net "GND")
		)
		(pad "161" smd rect
			(at 2.050034 -49.725072 270)
			(size 0.519938 1.4986)
			(layers "F.Cu" "F.Mask" "F.Paste")
			(net "M_D_CPU1_SA_DQ<7>")
		)
		(pad "162" smd rect
			(at 2.050034 -48.874934 270)
			(size 0.519938 1.4986)
			(layers "F.Cu" "F.Mask" "F.Paste")
			(net "GND")
		)
		(pad "163" smd rect
			(at 2.050034 -48.02505 270)
			(size 0.519938 1.4986)
			(layers "F.Cu" "F.Mask" "F.Paste")
			(net "M_D_CPU1_SA_DQ<10>")
		)
		(pad "164" smd rect
			(at 2.050034 -47.174912 270)
			(size 0.519938 1.4986)
			(layers "F.Cu" "F.Mask" "F.Paste")
			(net "GND")
		)
		(pad "165" smd rect
			(at 2.050034 -46.325028 270)
			(size 0.519938 1.4986)
			(layers "F.Cu" "F.Mask" "F.Paste")
			(net "M_D_CPU1_SA_DQ<11>")
		)
		(pad "166" smd rect
			(at 2.050034 -45.47489 270)
			(size 0.519938 1.4986)
			(layers "F.Cu" "F.Mask" "F.Paste")
			(net "GND")
		)
		(pad "167" smd rect
			(at 2.050034 -44.625006 270)
			(size 0.519938 1.4986)
			(layers "F.Cu" "F.Mask" "F.Paste")
			(net "M_D_CPU1_SA_DQS_DN<6>")
		)
		(pad "168" smd rect
			(at 2.050034 -43.775122 270)
			(size 0.519938 1.4986)
			(layers "F.Cu" "F.Mask" "F.Paste")
			(net "M_D_CPU1_SA_DQS_DP<6>")
		)
		(pad "169" smd rect
			(at 2.050034 -42.924984 270)
			(size 0.519938 1.4986)
			(layers "F.Cu" "F.Mask" "F.Paste")
			(net "GND")
		)
		(pad "170" smd rect
			(at 2.050034 -42.0751 270)
			(size 0.519938 1.4986)
			(layers "F.Cu" "F.Mask" "F.Paste")
			(net "M_D_CPU1_SA_DQ<14>")
		)
		(pad "171" smd rect
			(at 2.050034 -41.224962 270)
			(size 0.519938 1.4986)
			(layers "F.Cu" "F.Mask" "F.Paste")
			(net "GND")
		)
		(pad "172" smd rect
			(at 2.050034 -40.375078 270)
			(size 0.519938 1.4986)
			(layers "F.Cu" "F.Mask" "F.Paste")
			(net "M_D_CPU1_SA_DQ<15>")
		)
		(pad "173" smd rect
			(at 2.050034 -39.52494 270)
			(size 0.519938 1.4986)
			(layers "F.Cu" "F.Mask" "F.Paste")
			(net "GND")
		)
		(pad "174" smd rect
			(at 2.050034 -38.675056 270)
			(size 0.519938 1.4986)
			(layers "F.Cu" "F.Mask" "F.Paste")
			(net "M_D_CPU1_SA_DQ<18>")
		)
		(pad "175" smd rect
			(at 2.050034 -37.824918 270)
			(size 0.519938 1.4986)
			(layers "F.Cu" "F.Mask" "F.Paste")
			(net "GND")
		)
		(pad "176" smd rect
			(at 2.050034 -36.975034 270)
			(size 0.519938 1.4986)
			(layers "F.Cu" "F.Mask" "F.Paste")
			(net "M_D_CPU1_SA_DQ<19>")
		)
		(pad "177" smd rect
			(at 2.050034 -36.124896 270)
			(size 0.519938 1.4986)
			(layers "F.Cu" "F.Mask" "F.Paste")
			(net "GND")
		)
		(pad "178" smd rect
			(at 2.050034 -35.275012 270)
			(size 0.519938 1.4986)
			(layers "F.Cu" "F.Mask" "F.Paste")
			(net "M_D_CPU1_SA_DQS_DN<7>")
		)
		(pad "179" smd rect
			(at 2.050034 -34.425128 270)
			(size 0.519938 1.4986)
			(layers "F.Cu" "F.Mask" "F.Paste")
			(net "M_D_CPU1_SA_DQS_DP<7>")
		)
		(pad "180" smd rect
			(at 2.050034 -33.57499 270)
			(size 0.519938 1.4986)
			(layers "F.Cu" "F.Mask" "F.Paste")
			(net "GND")
		)
		(pad "181" smd rect
			(at 2.050034 -32.725106 270)
			(size 0.519938 1.4986)
			(layers "F.Cu" "F.Mask" "F.Paste")
			(net "M_D_CPU1_SA_DQ<22>")
		)
		(pad "182" smd rect
			(at 2.050034 -31.874968 270)
			(size 0.519938 1.4986)
			(layers "F.Cu" "F.Mask" "F.Paste")
			(net "GND")
		)
	)
)
